(kicad_pcb
	(version 20260206)
	(generator "pcbnew")
	(generator_version "10.0")
	(general
		(thickness 1.6)
		(legacy_teardrops no)
	)
	(paper "A4")
	(title_block
		(title "Wiwynn_Tioga_Pass_MB.brd")
		(comment 1 "Tioga Pass / footprints 1555-1562 of 4770")
	)
	(layers
		(0 "F.Cu" signal "TOP")
		(4 "In1.Cu" signal "L2GND")
		(6 "In2.Cu" signal "L3")
		(8 "In3.Cu" signal "L4GND")
		(10 "In4.Cu" signal "L5")
		(12 "In5.Cu" signal "L6GND")
		(14 "In6.Cu" signal "L7VCC")
		(16 "In7.Cu" signal "L8VCC")
		(18 "In8.Cu" signal "L9GND")
		(20 "In9.Cu" signal "L10")
		(22 "In10.Cu" signal "L11GND")
		(24 "In11.Cu" signal "L12")
		(26 "In12.Cu" signal "L13GND")
		(2 "B.Cu" signal "BOTTOM")
		(9 "F.Adhes" user "F.Adhesive")
		(11 "B.Adhes" user "B.Adhesive")
		(13 "F.Paste" user "Package Geometry/Pastemask Top")
		(15 "B.Paste" user "Package Geometry/Pastemask Bottom")
		(5 "F.SilkS" user "Ref Des/Silkscreen Top")
		(7 "B.SilkS" user "Ref Des/Silkscreen Bottom")
		(1 "F.Mask" user "Board Geometry/Soldermask Top")
		(3 "B.Mask" user "Board Geometry/Soldermask Bottom")
		(17 "Dwgs.User" user "User.Drawings")
		(19 "Cmts.User" user "User.Comments")
		(21 "Eco1.User" user "User.Eco1")
		(23 "Eco2.User" user "User.Eco2")
		(25 "Edge.Cuts" user "Board Geometry/Outline")
		(27 "Margin" user)
		(31 "F.CrtYd" user "Package Geometry/Place Bound Top")
		(29 "B.CrtYd" user "Package Geometry/Place Bound Bottom")
		(35 "F.Fab" user "Ref Des/Assembly Top")
		(33 "B.Fab" user "Ref Des/Assembly Bottom")
	)
	(footprint ""
		(layer "F.Cu")
		(at 333.849218 -129.921)
		(property "Reference" "C7B7"
			(at 0 0 0)
			(layer "F.SilkS")
			(hide yes)
			(effects
				(font
					(size 1.27 1.27)
				)
			)
		)
		(property "Value" ""
			(at 0 0 0)
			(layer "F.Fab")
			(effects
				(font
					(size 1.27 1.27)
				)
			)
		)
		(duplicate_pad_numbers_are_jumpers no)
		(fp_poly
			(pts
				(xy -0.7239 -0.2159) (xy 0.7239 -0.2159) (xy 0.7239 1.9939) (xy -0.7239 1.9939)
			)
			(stroke
				(width 0)
				(type default)
			)
			(fill no)
			(layer "F.CrtYd")
		)
		(fp_line
			(start -0.7239 -0.2159)
			(end -0.7239 1.9939)
			(stroke
				(width 0.1)
				(type default)
			)
			(layer "F.Fab")
		)
		(fp_line
			(start -0.7239 1.9939)
			(end 0.7239 1.9939)
			(stroke
				(width 0.1)
				(type default)
			)
			(layer "F.Fab")
		)
		(fp_line
			(start 0.7239 -0.2159)
			(end -0.7239 -0.2159)
			(stroke
				(width 0.1)
				(type default)
			)
			(layer "F.Fab")
		)
		(fp_line
			(start 0.7239 1.9939)
			(end 0.7239 -0.2159)
			(stroke
				(width 0.1)
				(type default)
			)
			(layer "F.Fab")
		)
		(pad "1" smd rect
			(at 0 0)
			(size 1.27 1.016)
			(layers "F.Cu" "F.Mask" "F.Paste")
			(net "PVPP_DEF")
		)
		(pad "2" smd rect
			(at 0 1.778)
			(size 1.27 1.016)
			(layers "F.Cu" "F.Mask" "F.Paste")
			(net "GND")
		)
		(zone
			(layer "F.Cu")
			(hatch none 0.5)
			(connect_pads
				(clearance 0)
			)
			(min_thickness 0.25)
			(keepout
				(tracks not_allowed)
				(vias allowed)
				(pads allowed)
				(copperpour not_allowed)
				(footprints allowed)
			)
			(placement
				(enabled no)
				(sheetname "")
			)
			(fill
				(thermal_gap 0.5)
				(thermal_bridge_width 0.5)
				(island_removal_mode 0)
			)
			(polygon
				(pts
					(xy 333.214218 -129.413) (xy 334.484218 -129.413) (xy 334.484218 -128.651) (xy 333.214218 -128.651)
				)
			)
		)
	)
	(footprint ""
		(layer "F.Cu")
		(at 18.288 -97.917 -90)
		(property "Reference" "C1C8"
			(at 0 0 270)
			(layer "F.SilkS")
			(hide yes)
			(effects
				(font
					(size 1.27 1.27)
				)
			)
		)
		(property "Value" ""
			(at 0 0 270)
			(layer "F.Fab")
			(effects
				(font
					(size 1.27 1.27)
				)
			)
		)
		(duplicate_pad_numbers_are_jumpers no)
		(fp_rect
			(start 0.3048 0.9906)
			(end -0.3048 -0.1016)
			(stroke
				(width 0)
				(type default)
			)
			(fill no)
			(layer "F.CrtYd")
		)
		(fp_line
			(start -0.3048 0.9906)
			(end 0.3048 0.9906)
			(stroke
				(width 0.1)
				(type default)
			)
			(layer "F.Fab")
		)
		(fp_line
			(start 0.3048 0.9906)
			(end 0.3048 -0.1016)
			(stroke
				(width 0.1)
				(type default)
			)
			(layer "F.Fab")
		)
		(fp_line
			(start -0.3048 -0.1016)
			(end -0.3048 0.9906)
			(stroke
				(width 0.1)
				(type default)
			)
			(layer "F.Fab")
		)
		(fp_line
			(start 0.3048 -0.1016)
			(end -0.3048 -0.1016)
			(stroke
				(width 0.1)
				(type default)
			)
			(layer "F.Fab")
		)
		(pad "1" smd rect
			(at 0 0 270)
			(size 0.508 0.508)
			(layers "F.Cu" "F.Mask" "F.Paste")
			(net "VR_PVCCIN_CPU1_AVINSEN")
		)
		(pad "2" smd rect
			(at 0 0.889 270)
			(size 0.508 0.508)
			(layers "F.Cu" "F.Mask" "F.Paste")
			(net "GND")
		)
		(zone
			(layer "F.Cu")
			(hatch none 0.5)
			(connect_pads
				(clearance 0)
			)
			(min_thickness 0.25)
			(keepout
				(tracks allowed)
				(vias not_allowed)
				(pads allowed)
				(copperpour not_allowed)
				(footprints allowed)
			)
			(placement
				(enabled no)
				(sheetname "")
			)
			(fill
				(thermal_gap 0.5)
				(thermal_bridge_width 0.5)
				(island_removal_mode 0)
			)
			(polygon
				(pts
					(xy 17.653 -97.663) (xy 18.034 -97.663) (xy 18.034 -98.171) (xy 17.653 -98.171)
				)
			)
		)
		(zone
			(layer "F.Cu")
			(hatch none 0.5)
			(connect_pads
				(clearance 0)
			)
			(min_thickness 0.25)
			(keepout
				(tracks not_allowed)
				(vias allowed)
				(pads allowed)
				(copperpour not_allowed)
				(footprints allowed)
			)
			(placement
				(enabled no)
				(sheetname "")
			)
			(fill
				(thermal_gap 0.5)
				(thermal_bridge_width 0.5)
				(island_removal_mode 0)
			)
			(polygon
				(pts
					(xy 17.653 -97.663) (xy 18.034 -97.663) (xy 18.034 -98.171) (xy 17.653 -98.171)
				)
			)
		)
	)
	(footprint ""
		(layer "F.Cu")
		(at 113.867692 -71.714614 180)
		(property "Reference" "C3D23"
			(at 0 0 180)
			(layer "F.SilkS")
			(hide yes)
			(effects
				(font
					(size 1.27 1.27)
				)
			)
		)
		(property "Value" ""
			(at 0 0 180)
			(layer "F.Fab")
			(effects
				(font
					(size 1.27 1.27)
				)
			)
		)
		(duplicate_pad_numbers_are_jumpers no)
		(fp_poly
			(pts
				(xy -0.4953 -0.2032) (xy 0.4953 -0.2032) (xy 0.4953 1.6002) (xy -0.4953 1.6002)
			)
			(stroke
				(width 0)
				(type default)
			)
			(fill no)
			(layer "F.CrtYd")
		)
		(fp_line
			(start 0.4953 1.6002)
			(end -0.4953 1.6002)
			(stroke
				(width 0.1)
				(type default)
			)
			(layer "F.Fab")
		)
		(fp_line
			(start 0.4953 -0.2032)
			(end 0.4953 1.6002)
			(stroke
				(width 0.1)
				(type default)
			)
			(layer "F.Fab")
		)
		(fp_line
			(start -0.4953 1.6002)
			(end -0.4953 -0.2032)
			(stroke
				(width 0.1)
				(type default)
			)
			(layer "F.Fab")
		)
		(fp_line
			(start -0.4953 -0.2032)
			(end 0.4953 -0.2032)
			(stroke
				(width 0.1)
				(type default)
			)
			(layer "F.Fab")
		)
		(pad "1" smd rect
			(at 0 0 180)
			(size 0.762 0.889)
			(layers "F.Cu" "F.Mask" "F.Paste")
			(net "PVCCIO_CPU1")
		)
		(pad "2" smd rect
			(at 0 1.397 180)
			(size 0.762 0.889)
			(layers "F.Cu" "F.Mask" "F.Paste")
			(net "GND")
		)
		(zone
			(layer "F.Cu")
			(hatch none 0.5)
			(connect_pads
				(clearance 0)
			)
			(min_thickness 0.25)
			(keepout
				(tracks not_allowed)
				(vias allowed)
				(pads allowed)
				(copperpour not_allowed)
				(footprints allowed)
			)
			(placement
				(enabled no)
				(sheetname "")
			)
			(fill
				(thermal_gap 0.5)
				(thermal_bridge_width 0.5)
				(island_removal_mode 0)
			)
			(polygon
				(pts
					(xy 114.248692 -72.159114) (xy 113.486692 -72.159114) (xy 113.486692 -72.667114) (xy 114.248692 -72.667114)
				)
			)
		)
	)
	(footprint ""
		(layer "F.Cu")
		(at 318.8716 -30.585918 -90)
		(property "Reference" "R6F10"
			(at 0 0 270)
			(layer "F.SilkS")
			(hide yes)
			(effects
				(font
					(size 1.27 1.27)
				)
			)
		)
		(property "Value" ""
			(at 0 0 270)
			(layer "F.Fab")
			(effects
				(font
					(size 1.27 1.27)
				)
			)
		)
		(duplicate_pad_numbers_are_jumpers no)
		(fp_poly
			(pts
				(xy -0.2794 -0.1016) (xy 0.2794 -0.1016) (xy 0.2794 0.9906) (xy -0.2794 0.9906)
			)
			(stroke
				(width 0)
				(type default)
			)
			(fill no)
			(layer "F.CrtYd")
		)
		(fp_line
			(start -0.2794 0.9906)
			(end 0.2794 0.9906)
			(stroke
				(width 0.1)
				(type default)
			)
			(layer "F.Fab")
		)
		(fp_line
			(start 0.2794 0.9906)
			(end 0.2794 -0.1016)
			(stroke
				(width 0.1)
				(type default)
			)
			(layer "F.Fab")
		)
		(fp_line
			(start -0.2794 -0.1016)
			(end -0.2794 0.9906)
			(stroke
				(width 0.1)
				(type default)
			)
			(layer "F.Fab")
		)
		(fp_line
			(start 0.2794 -0.1016)
			(end -0.2794 -0.1016)
			(stroke
				(width 0.1)
				(type default)
			)
			(layer "F.Fab")
		)
		(pad "1" smd rect
			(at 0 0 270)
			(size 0.508 0.508)
			(layers "F.Cu" "F.Mask" "F.Paste")
			(net "CLK_322M_156M_CPU0_OSC_VRM_DN")
		)
		(pad "2" smd rect
			(at 0 0.889 270)
			(size 0.508 0.508)
			(layers "F.Cu" "F.Mask" "F.Paste")
			(net "CLK_322M_OSC_CPU0_RC_DN")
		)
		(zone
			(layer "F.Cu")
			(hatch none 0.5)
			(connect_pads
				(clearance 0)
			)
			(min_thickness 0.25)
			(keepout
				(tracks not_allowed)
				(vias allowed)
				(pads allowed)
				(copperpour not_allowed)
				(footprints allowed)
			)
			(placement
				(enabled no)
				(sheetname "")
			)
			(fill
				(thermal_gap 0.5)
				(thermal_bridge_width 0.5)
				(island_removal_mode 0)
			)
			(polygon
				(pts
					(xy 318.2366 -30.839918) (xy 318.2366 -30.331918) (xy 318.6176 -30.331918) (xy 318.6176 -30.839918)
				)
			)
		)
		(zone
			(layer "F.Cu")
			(hatch none 0.5)
			(connect_pads
				(clearance 0)
			)
			(min_thickness 0.25)
			(keepout
				(tracks allowed)
				(vias not_allowed)
				(pads allowed)
				(copperpour not_allowed)
				(footprints allowed)
			)
			(placement
				(enabled no)
				(sheetname "")
			)
			(fill
				(thermal_gap 0.5)
				(thermal_bridge_width 0.5)
				(island_removal_mode 0)
			)
			(polygon
				(pts
					(xy 318.6176 -30.839918) (xy 318.6176 -30.331918) (xy 318.2366 -30.331918) (xy 318.2366 -30.839918)
				)
			)
		)
	)
	(footprint ""
		(layer "F.Cu")
		(at 193.8782 -58.928 90)
		(property "Reference" "C4E17"
			(at 0 0 90)
			(layer "F.SilkS")
			(hide yes)
			(effects
				(font
					(size 1.27 1.27)
				)
			)
		)
		(property "Value" ""
			(at 0 0 90)
			(layer "F.Fab")
			(effects
				(font
					(size 1.27 1.27)
				)
			)
		)
		(duplicate_pad_numbers_are_jumpers no)
		(fp_rect
			(start -0.3048 0.9906)
			(end 0.3048 -0.1016)
			(stroke
				(width 0)
				(type default)
			)
			(fill no)
			(layer "F.CrtYd")
		)
		(fp_line
			(start 0.3048 -0.1016)
			(end -0.3048 -0.1016)
			(stroke
				(width 0.1)
				(type default)
			)
			(layer "F.Fab")
		)
		(fp_line
			(start -0.3048 -0.1016)
			(end -0.3048 0.9906)
			(stroke
				(width 0.1)
				(type default)
			)
			(layer "F.Fab")
		)
		(fp_line
			(start 0.3048 0.9906)
			(end 0.3048 -0.1016)
			(stroke
				(width 0.1)
				(type default)
			)
			(layer "F.Fab")
		)
		(fp_line
			(start -0.3048 0.9906)
			(end 0.3048 0.9906)
			(stroke
				(width 0.1)
				(type default)
			)
			(layer "F.Fab")
		)
		(pad "1" smd rect
			(at 0 0 90)
			(size 0.508 0.508)
			(layers "F.Cu" "F.Mask" "F.Paste")
			(net "VR_PVCCIN_CPU0_PH1_BOOT")
		)
		(pad "2" smd rect
			(at 0 0.889 90)
			(size 0.508 0.508)
			(layers "F.Cu" "F.Mask" "F.Paste")
			(net "VR_PVCCIN_CPU0_PH1_PHASE")
		)
		(zone
			(layer "F.Cu")
			(hatch none 0.5)
			(connect_pads
				(clearance 0)
			)
			(min_thickness 0.25)
			(keepout
				(tracks allowed)
				(vias not_allowed)
				(pads allowed)
				(copperpour not_allowed)
				(footprints allowed)
			)
			(placement
				(enabled no)
				(sheetname "")
			)
			(fill
				(thermal_gap 0.5)
				(thermal_bridge_width 0.5)
				(island_removal_mode 0)
			)
			(polygon
				(pts
					(xy 194.5132 -58.674) (xy 194.5132 -59.182) (xy 194.1322 -59.182) (xy 194.1322 -58.674)
				)
			)
		)
		(zone
			(layer "F.Cu")
			(hatch none 0.5)
			(connect_pads
				(clearance 0)
			)
			(min_thickness 0.25)
			(keepout
				(tracks not_allowed)
				(vias allowed)
				(pads allowed)
				(copperpour not_allowed)
				(footprints allowed)
			)
			(placement
				(enabled no)
				(sheetname "")
			)
			(fill
				(thermal_gap 0.5)
				(thermal_bridge_width 0.5)
				(island_removal_mode 0)
			)
			(polygon
				(pts
					(xy 194.5132 -58.674) (xy 194.5132 -59.182) (xy 194.1322 -59.182) (xy 194.1322 -58.674)
				)
			)
		)
	)
	(footprint ""
		(layer "F.Cu")
		(at 272.134838 -68.365116 180)
		(property "Reference" "C5D61"
			(at 0 0 180)
			(layer "F.SilkS")
			(hide yes)
			(effects
				(font
					(size 1.27 1.27)
				)
			)
		)
		(property "Value" ""
			(at 0 0 180)
			(layer "F.Fab")
			(effects
				(font
					(size 1.27 1.27)
				)
			)
		)
		(duplicate_pad_numbers_are_jumpers no)
		(fp_poly
			(pts
				(xy -0.4953 -0.2032) (xy 0.4953 -0.2032) (xy 0.4953 1.6002) (xy -0.4953 1.6002)
			)
			(stroke
				(width 0)
				(type default)
			)
			(fill no)
			(layer "F.CrtYd")
		)
		(fp_line
			(start 0.4953 1.6002)
			(end -0.4953 1.6002)
			(stroke
				(width 0.1)
				(type default)
			)
			(layer "F.Fab")
		)
		(fp_line
			(start 0.4953 -0.2032)
			(end 0.4953 1.6002)
			(stroke
				(width 0.1)
				(type default)
			)
			(layer "F.Fab")
		)
		(fp_line
			(start -0.4953 1.6002)
			(end -0.4953 -0.2032)
			(stroke
				(width 0.1)
				(type default)
			)
			(layer "F.Fab")
		)
		(fp_line
			(start -0.4953 -0.2032)
			(end 0.4953 -0.2032)
			(stroke
				(width 0.1)
				(type default)
			)
			(layer "F.Fab")
		)
		(pad "1" smd rect
			(at 0 0 180)
			(size 0.762 0.889)
			(layers "F.Cu" "F.Mask" "F.Paste")
			(net "PVDDQ_ABC")
		)
		(pad "2" smd rect
			(at 0 1.397 180)
			(size 0.762 0.889)
			(layers "F.Cu" "F.Mask" "F.Paste")
			(net "GND")
		)
		(zone
			(layer "F.Cu")
			(hatch none 0.5)
			(connect_pads
				(clearance 0)
			)
			(min_thickness 0.25)
			(keepout
				(tracks not_allowed)
				(vias allowed)
				(pads allowed)
				(copperpour not_allowed)
				(footprints allowed)
			)
			(placement
				(enabled no)
				(sheetname "")
			)
			(fill
				(thermal_gap 0.5)
				(thermal_bridge_width 0.5)
				(island_removal_mode 0)
			)
			(polygon
				(pts
					(xy 272.515838 -68.809616) (xy 271.753838 -68.809616) (xy 271.753838 -69.317616) (xy 272.515838 -69.317616)
				)
			)
		)
	)
	(footprint ""
		(layer "F.Cu")
		(at 451.866 -26.8478 90)
		(property "Reference" "C1W15"
			(at 0.97536 0.76708 0)
			(unlocked yes)
			(layer "F.SilkS")
			(effects
				(font
					(size 0.4064 0.254)
					(thickness 0.1524)
				)
			)
		)
		(property "Value" ""
			(at 0 0 90)
			(layer "F.Fab")
			(effects
				(font
					(size 1.27 1.27)
				)
			)
		)
		(duplicate_pad_numbers_are_jumpers no)
		(fp_poly
			(pts
				(xy -0.4953 -0.2032) (xy 0.4953 -0.2032) (xy 0.4953 1.6002) (xy -0.4953 1.6002)
			)
			(stroke
				(width 0)
				(type default)
			)
			(fill no)
			(layer "F.CrtYd")
		)
		(fp_line
			(start 0.4953 -0.2032)
			(end 0.4953 1.6002)
			(stroke
				(width 0.1)
				(type default)
			)
			(layer "F.Fab")
		)
		(fp_line
			(start -0.4953 -0.2032)
			(end 0.4953 -0.2032)
			(stroke
				(width 0.1)
				(type default)
			)
			(layer "F.Fab")
		)
		(fp_line
			(start 0.4953 1.6002)
			(end -0.4953 1.6002)
			(stroke
				(width 0.1)
				(type default)
			)
			(layer "F.Fab")
		)
		(fp_line
			(start -0.4953 1.6002)
			(end -0.4953 -0.2032)
			(stroke
				(width 0.1)
				(type default)
			)
			(layer "F.Fab")
		)
		(pad "1" smd rect
			(at 0 0 90)
			(size 0.762 0.889)
			(layers "F.Cu" "F.Mask" "F.Paste")
			(net "P2V5_AUX_BMC")
		)
		(pad "2" smd rect
			(at 0 1.397 90)
			(size 0.762 0.889)
			(layers "F.Cu" "F.Mask" "F.Paste")
			(net "GND")
		)
		(zone
			(layer "F.Cu")
			(hatch none 0.5)
			(connect_pads
				(clearance 0)
			)
			(min_thickness 0.25)
			(keepout
				(tracks not_allowed)
				(vias allowed)
				(pads allowed)
				(copperpour not_allowed)
				(footprints allowed)
			)
			(placement
				(enabled no)
				(sheetname "")
			)
			(fill
				(thermal_gap 0.5)
				(thermal_bridge_width 0.5)
				(island_removal_mode 0)
			)
			(polygon
				(pts
					(xy 452.3105 -26.4668) (xy 452.3105 -27.2288) (xy 452.8185 -27.2288) (xy 452.8185 -26.4668)
				)
			)
		)
	)
	(footprint ""
		(layer "F.Cu")
		(at 451.85838 -31.3055 90)
		(property "Reference" "R25W34"
			(at 0 0 90)
			(layer "F.SilkS")
			(hide yes)
			(effects
				(font
					(size 1.27 1.27)
				)
			)
		)
		(property "Value" "*"
			(at 0.064008 -4.108196 90)
			(unlocked yes)
			(layer "F.Fab")
			(hide yes)
			(effects
				(font
					(size 1.27 1.016)
					(thickness 0.1524)
				)
			)
		)
		(property "Device Type" "120R2F-GP_RCL_GP-120R2F-GP,64.A"
			(at 0.064008 -5.632196 90)
			(unlocked yes)
			(layer "F.Fab")
			(hide yes)
			(effects
				(font
					(size 1.27 1.016)
					(thickness 0.1524)
				)
			)
		)
		(duplicate_pad_numbers_are_jumpers no)
		(fp_line
			(start 0.508 -0.9398)
			(end -0.508 -0.9398)
			(stroke
				(width 0.1524)
				(type default)
			)
			(layer "F.SilkS")
		)
		(fp_line
			(start -0.508 -0.9398)
			(end -0.508 0.9398)
			(stroke
				(width 0.1524)
				(type default)
			)
			(layer "F.SilkS")
		)
		(fp_rect
			(start -0.508 0.9398)
			(end 0.508 -0.9398)
			(stroke
				(width 0)
				(type default)
			)
			(fill no)
			(layer "F.CrtYd")
		)
		(fp_rect
			(start -0.508 0.9398)
			(end 0.508 -0.9398)
			(stroke
				(width 0)
				(type default)
			)
			(fill no)
			(layer "F.Fab")
		)
		(pad "1" smd custom
			(at 0 -0.4445 90)
			(size 0.1397 0.1397)
			(layers "F.Cu" "F.Mask" "F.Paste")
			(net "BMC_M_WE_N")
			(options
				(clearance outline)
				(anchor circle)
			)
			(primitives
				(gr_poly
					(pts
						(arc
							(start -0.1778 -0.2794)
							(mid -0.249642 -0.249642)
							(end -0.2794 -0.1778)
						)
						(arc
							(start -0.2794 0.1778)
							(mid -0.249642 0.249642)
							(end -0.1778 0.2794)
						)
						(arc
							(start 0.1778 0.2794)
							(mid 0.249642 0.249642)
							(end 0.2794 0.1778)
						)
						(arc
							(start 0.2794 -0.1778)
							(mid 0.249642 -0.249642)
							(end 0.1778 -0.2794)
						)
					)
					(width 0)
					(fill yes)
				)
			)
		)
		(pad "2" smd custom
			(at 0 0.4445 90)
			(size 0.1397 0.1397)
			(layers "F.Cu" "F.Mask" "F.Paste")
			(net "P1V2_AUX_BMC")
			(options
				(clearance outline)
				(anchor circle)
			)
			(primitives
				(gr_poly
					(pts
						(arc
							(start -0.1778 -0.2794)
							(mid -0.249642 -0.249642)
							(end -0.2794 -0.1778)
						)
						(arc
							(start -0.2794 0.1778)
							(mid -0.249642 0.249642)
							(end -0.1778 0.2794)
						)
						(arc
							(start 0.1778 0.2794)
							(mid 0.249642 0.249642)
							(end 0.2794 0.1778)
						)
						(arc
							(start 0.2794 -0.1778)
							(mid 0.249642 -0.249642)
							(end 0.1778 -0.2794)
						)
					)
					(width 0)
					(fill yes)
				)
			)
		)
	)
)
